(kicad_pcb
	(version 20260206)
	(generator "pcbnew")
	(generator_version "10.0")
	(general
		(thickness 1.6)
		(legacy_teardrops no)
	)
	(paper "A4")
	(title_block
		(title "12092022_DA0F0TMDCD0_F0T_Management_Board_D_brd_V3_OCP.brd")
		(comment 1 "Grand Teton / footprints 312-317 of 1440")
	)
	(layers
		(0 "F.Cu" signal "TOP")
		(4 "In1.Cu" signal "GND")
		(6 "In2.Cu" signal "IN1")
		(8 "In3.Cu" signal "GND1")
		(10 "In4.Cu" signal "IN2")
		(12 "In5.Cu" signal "VCC")
		(14 "In6.Cu" signal "VCC1")
		(16 "In7.Cu" signal "IN3")
		(18 "In8.Cu" signal "GND2")
		(20 "In9.Cu" signal "IN4")
		(22 "In10.Cu" signal "GND3")
		(2 "B.Cu" signal "BOTTOM")
		(9 "F.Adhes" user "F.Adhesive")
		(11 "B.Adhes" user "B.Adhesive")
		(13 "F.Paste" user "Package Geometry/Pastemask Top")
		(15 "B.Paste" user "Package Geometry/Pastemask Bottom")
		(5 "F.SilkS" user "Ref Des/Silkscreen Top")
		(7 "B.SilkS" user "Ref Des/Silkscreen Bottom")
		(1 "F.Mask" user "Board Geometry/Soldermask Top")
		(3 "B.Mask" user "Board Geometry/Soldermask Bottom")
		(17 "Dwgs.User" user "User.Drawings")
		(19 "Cmts.User" user "User.Comments")
		(21 "Eco1.User" user "User.Eco1")
		(23 "Eco2.User" user "User.Eco2")
		(25 "Edge.Cuts" user "Board Geometry/Outline")
		(27 "Margin" user)
		(31 "F.CrtYd" user "Package Geometry/Place Bound Top")
		(29 "B.CrtYd" user "Package Geometry/Place Bound Bottom")
		(35 "F.Fab" user "Ref Des/Assembly Top")
		(33 "B.Fab" user "Ref Des/Assembly Bottom")
	)
	(footprint ""
		(layer "F.Cu")
		(at 35.5346 -109.347 90)
		(property "Reference" "R69"
			(at 0 0 90)
			(layer "F.SilkS")
			(hide yes)
			(effects
				(font
					(size 1.27 1.27)
				)
			)
		)
		(property "Value" ""
			(at 0 0 90)
			(layer "F.Fab")
			(effects
				(font
					(size 1.27 1.27)
				)
			)
		)
		(duplicate_pad_numbers_are_jumpers no)
		(fp_line
			(start 0.7874 -0.4064)
			(end 0.7874 0.4064)
			(stroke
				(width 0.1524)
				(type default)
			)
			(layer "F.SilkS")
		)
		(fp_line
			(start -0.7874 -0.4064)
			(end 0.7874 -0.4064)
			(stroke
				(width 0.1524)
				(type default)
			)
			(layer "F.SilkS")
		)
		(fp_line
			(start 0.7874 0.4064)
			(end -0.7874 0.4064)
			(stroke
				(width 0.1524)
				(type default)
			)
			(layer "F.SilkS")
		)
		(fp_line
			(start -0.7874 0.4064)
			(end -0.7874 -0.4064)
			(stroke
				(width 0.1524)
				(type default)
			)
			(layer "F.SilkS")
		)
		(fp_line
			(start -0.12065 -0.305054)
			(end -0.12065 -0.2794)
			(stroke
				(width 0.1)
				(type default)
			)
			(layer "F.Fab")
		)
		(fp_line
			(start -0.67945 -0.305054)
			(end -0.12065 -0.305054)
			(stroke
				(width 0.1)
				(type default)
			)
			(layer "F.Fab")
		)
		(fp_line
			(start 0.67945 -0.3048)
			(end 0.67945 0.3048)
			(stroke
				(width 0.1)
				(type default)
			)
			(layer "F.Fab")
		)
		(fp_line
			(start 0.12065 -0.3048)
			(end 0.67945 -0.3048)
			(stroke
				(width 0.1)
				(type default)
			)
			(layer "F.Fab")
		)
		(fp_line
			(start 0.12065 -0.2794)
			(end 0.12065 -0.3048)
			(stroke
				(width 0.1)
				(type default)
			)
			(layer "F.Fab")
		)
		(fp_line
			(start -0.12065 -0.2794)
			(end 0.12065 -0.2794)
			(stroke
				(width 0.1)
				(type default)
			)
			(layer "F.Fab")
		)
		(fp_line
			(start 0.120396 0.2794)
			(end -0.12065 0.2794)
			(stroke
				(width 0.1)
				(type default)
			)
			(layer "F.Fab")
		)
		(fp_line
			(start -0.12065 0.2794)
			(end -0.12065 0.3048)
			(stroke
				(width 0.1)
				(type default)
			)
			(layer "F.Fab")
		)
		(fp_line
			(start 0.67945 0.3048)
			(end 0.120396 0.3048)
			(stroke
				(width 0.1)
				(type default)
			)
			(layer "F.Fab")
		)
		(fp_line
			(start 0.120396 0.3048)
			(end 0.120396 0.2794)
			(stroke
				(width 0.1)
				(type default)
			)
			(layer "F.Fab")
		)
		(fp_line
			(start -0.12065 0.3048)
			(end -0.67945 0.3048)
			(stroke
				(width 0.1)
				(type default)
			)
			(layer "F.Fab")
		)
		(fp_line
			(start -0.67945 0.3048)
			(end -0.67945 -0.305054)
			(stroke
				(width 0.1)
				(type default)
			)
			(layer "F.Fab")
		)
		(pad "1" smd circle
			(at -0.40005 0 90)
			(size 0 0)
			(layers "F.Cu" "F.Mask" "F.Paste")
			(net "P3V3_AUX")
		)
		(pad "2" smd circle
			(at 0.40005 0 90)
			(size 0 0)
			(layers "F.Cu" "F.Mask" "F.Paste")
			(net "RST_SGPIO_RESET_N")
		)
	)
	(footprint ""
		(layer "F.Cu")
		(at 80.6704 -15.9258)
		(property "Reference" "C201"
			(at 0 0 0)
			(layer "F.SilkS")
			(hide yes)
			(effects
				(font
					(size 1.27 1.27)
				)
			)
		)
		(property "Value" ""
			(at 0 0 0)
			(layer "F.Fab")
			(effects
				(font
					(size 1.27 1.27)
				)
			)
		)
		(duplicate_pad_numbers_are_jumpers no)
		(fp_line
			(start -0.7874 -0.4064)
			(end 0.7874 -0.4064)
			(stroke
				(width 0.1524)
				(type default)
			)
			(layer "F.SilkS")
		)
		(fp_line
			(start -0.7874 0.4064)
			(end -0.7874 -0.4064)
			(stroke
				(width 0.1524)
				(type default)
			)
			(layer "F.SilkS")
		)
		(fp_line
			(start 0.7874 -0.4064)
			(end 0.7874 0.4064)
			(stroke
				(width 0.1524)
				(type default)
			)
			(layer "F.SilkS")
		)
		(fp_line
			(start 0.7874 0.4064)
			(end -0.7874 0.4064)
			(stroke
				(width 0.1524)
				(type default)
			)
			(layer "F.SilkS")
		)
		(fp_line
			(start -0.67945 -0.305054)
			(end -0.12065 -0.305054)
			(stroke
				(width 0.1)
				(type default)
			)
			(layer "F.Fab")
		)
		(fp_line
			(start -0.67945 0.3048)
			(end -0.67945 -0.305054)
			(stroke
				(width 0.1)
				(type default)
			)
			(layer "F.Fab")
		)
		(fp_line
			(start -0.12065 -0.305054)
			(end -0.12065 -0.2794)
			(stroke
				(width 0.1)
				(type default)
			)
			(layer "F.Fab")
		)
		(fp_line
			(start -0.12065 -0.2794)
			(end 0.12065 -0.2794)
			(stroke
				(width 0.1)
				(type default)
			)
			(layer "F.Fab")
		)
		(fp_line
			(start -0.12065 0.2794)
			(end -0.12065 0.3048)
			(stroke
				(width 0.1)
				(type default)
			)
			(layer "F.Fab")
		)
		(fp_line
			(start -0.12065 0.3048)
			(end -0.67945 0.3048)
			(stroke
				(width 0.1)
				(type default)
			)
			(layer "F.Fab")
		)
		(fp_line
			(start 0.120396 0.2794)
			(end -0.12065 0.2794)
			(stroke
				(width 0.1)
				(type default)
			)
			(layer "F.Fab")
		)
		(fp_line
			(start 0.120396 0.3048)
			(end 0.120396 0.2794)
			(stroke
				(width 0.1)
				(type default)
			)
			(layer "F.Fab")
		)
		(fp_line
			(start 0.12065 -0.3048)
			(end 0.67945 -0.3048)
			(stroke
				(width 0.1)
				(type default)
			)
			(layer "F.Fab")
		)
		(fp_line
			(start 0.12065 -0.2794)
			(end 0.12065 -0.3048)
			(stroke
				(width 0.1)
				(type default)
			)
			(layer "F.Fab")
		)
		(fp_line
			(start 0.67945 -0.3048)
			(end 0.67945 0.3048)
			(stroke
				(width 0.1)
				(type default)
			)
			(layer "F.Fab")
		)
		(fp_line
			(start 0.67945 0.3048)
			(end 0.120396 0.3048)
			(stroke
				(width 0.1)
				(type default)
			)
			(layer "F.Fab")
		)
		(pad "1" smd circle
			(at -0.40005 0)
			(size 0 0)
			(layers "F.Cu" "F.Mask" "F.Paste")
			(net "P3V3_AUX")
		)
		(pad "2" smd circle
			(at 0.40005 0)
			(size 0 0)
			(layers "F.Cu" "F.Mask" "F.Paste")
			(net "GND")
		)
	)
	(footprint ""
		(layer "F.Cu")
		(at 20.701 -56.1848 90)
		(property "Reference" "R538"
			(at 0 0 90)
			(layer "F.SilkS")
			(hide yes)
			(effects
				(font
					(size 1.27 1.27)
				)
			)
		)
		(property "Value" ""
			(at 0 0 90)
			(layer "F.Fab")
			(effects
				(font
					(size 1.27 1.27)
				)
			)
		)
		(duplicate_pad_numbers_are_jumpers no)
		(fp_line
			(start 0.7874 -0.4064)
			(end 0.7874 0.4064)
			(stroke
				(width 0.1524)
				(type default)
			)
			(layer "F.SilkS")
		)
		(fp_line
			(start -0.7874 -0.4064)
			(end 0.7874 -0.4064)
			(stroke
				(width 0.1524)
				(type default)
			)
			(layer "F.SilkS")
		)
		(fp_line
			(start 0.7874 0.4064)
			(end -0.7874 0.4064)
			(stroke
				(width 0.1524)
				(type default)
			)
			(layer "F.SilkS")
		)
		(fp_line
			(start -0.7874 0.4064)
			(end -0.7874 -0.4064)
			(stroke
				(width 0.1524)
				(type default)
			)
			(layer "F.SilkS")
		)
		(fp_line
			(start -0.12065 -0.305054)
			(end -0.12065 -0.2794)
			(stroke
				(width 0.1)
				(type default)
			)
			(layer "F.Fab")
		)
		(fp_line
			(start -0.67945 -0.305054)
			(end -0.12065 -0.305054)
			(stroke
				(width 0.1)
				(type default)
			)
			(layer "F.Fab")
		)
		(fp_line
			(start 0.67945 -0.3048)
			(end 0.67945 0.3048)
			(stroke
				(width 0.1)
				(type default)
			)
			(layer "F.Fab")
		)
		(fp_line
			(start 0.12065 -0.3048)
			(end 0.67945 -0.3048)
			(stroke
				(width 0.1)
				(type default)
			)
			(layer "F.Fab")
		)
		(fp_line
			(start 0.12065 -0.2794)
			(end 0.12065 -0.3048)
			(stroke
				(width 0.1)
				(type default)
			)
			(layer "F.Fab")
		)
		(fp_line
			(start -0.12065 -0.2794)
			(end 0.12065 -0.2794)
			(stroke
				(width 0.1)
				(type default)
			)
			(layer "F.Fab")
		)
		(fp_line
			(start 0.120396 0.2794)
			(end -0.12065 0.2794)
			(stroke
				(width 0.1)
				(type default)
			)
			(layer "F.Fab")
		)
		(fp_line
			(start -0.12065 0.2794)
			(end -0.12065 0.3048)
			(stroke
				(width 0.1)
				(type default)
			)
			(layer "F.Fab")
		)
		(fp_line
			(start 0.67945 0.3048)
			(end 0.120396 0.3048)
			(stroke
				(width 0.1)
				(type default)
			)
			(layer "F.Fab")
		)
		(fp_line
			(start 0.120396 0.3048)
			(end 0.120396 0.2794)
			(stroke
				(width 0.1)
				(type default)
			)
			(layer "F.Fab")
		)
		(fp_line
			(start -0.12065 0.3048)
			(end -0.67945 0.3048)
			(stroke
				(width 0.1)
				(type default)
			)
			(layer "F.Fab")
		)
		(fp_line
			(start -0.67945 0.3048)
			(end -0.67945 -0.305054)
			(stroke
				(width 0.1)
				(type default)
			)
			(layer "F.Fab")
		)
		(pad "1" smd circle
			(at -0.40005 0 90)
			(size 0 0)
			(layers "F.Cu" "F.Mask" "F.Paste")
			(net "P3V3_AUX")
		)
		(pad "2" smd circle
			(at 0.40005 0 90)
			(size 0 0)
			(layers "F.Cu" "F.Mask" "F.Paste")
			(net "UART_6_BMC_RXD_R")
		)
	)
	(footprint ""
		(layer "F.Cu")
		(at 19.3421 -35.967162 180)
		(property "Reference" "PC261"
			(at 0 0 180)
			(layer "F.SilkS")
			(hide yes)
			(effects
				(font
					(size 1.27 1.27)
				)
			)
		)
		(property "Value" ""
			(at 0 0 180)
			(layer "F.Fab")
			(effects
				(font
					(size 1.27 1.27)
				)
			)
		)
		(duplicate_pad_numbers_are_jumpers no)
		(fp_line
			(start 1.651 0.8382)
			(end -1.651 0.8382)
			(stroke
				(width 0.1524)
				(type default)
			)
			(layer "F.SilkS")
		)
		(fp_line
			(start 1.651 -0.8382)
			(end 1.651 0.8382)
			(stroke
				(width 0.1524)
				(type default)
			)
			(layer "F.SilkS")
		)
		(fp_line
			(start 0 0.8382)
			(end 0 -0.8382)
			(stroke
				(width 0.1524)
				(type default)
			)
			(layer "F.SilkS")
		)
		(fp_line
			(start -1.651 0.8382)
			(end -1.651 -0.8382)
			(stroke
				(width 0.1524)
				(type default)
			)
			(layer "F.SilkS")
		)
		(fp_line
			(start -1.651 -0.8382)
			(end 1.651 -0.8382)
			(stroke
				(width 0.1524)
				(type default)
			)
			(layer "F.SilkS")
		)
		(fp_line
			(start 1.55956 0.7366)
			(end 1.55956 -0.7366)
			(stroke
				(width 0.1)
				(type default)
			)
			(layer "F.Fab")
		)
		(fp_line
			(start 1.55956 -0.7366)
			(end 1.524 -0.7366)
			(stroke
				(width 0.1)
				(type default)
			)
			(layer "F.Fab")
		)
		(fp_line
			(start 1.524 0.7366)
			(end 1.55956 0.7366)
			(stroke
				(width 0.1)
				(type default)
			)
			(layer "F.Fab")
		)
		(fp_line
			(start 1.524 -0.7366)
			(end -1.524 -0.7366)
			(stroke
				(width 0.1)
				(type default)
			)
			(layer "F.Fab")
		)
		(fp_line
			(start -1.524 0.7366)
			(end 1.524 0.7366)
			(stroke
				(width 0.1)
				(type default)
			)
			(layer "F.Fab")
		)
		(fp_line
			(start -1.524 -0.7366)
			(end -1.55956 -0.7366)
			(stroke
				(width 0.1)
				(type default)
			)
			(layer "F.Fab")
		)
		(fp_line
			(start -1.55956 0.7366)
			(end -1.524 0.7366)
			(stroke
				(width 0.1)
				(type default)
			)
			(layer "F.Fab")
		)
		(fp_line
			(start -1.55956 -0.7366)
			(end -1.55956 0.7366)
			(stroke
				(width 0.1)
				(type default)
			)
			(layer "F.Fab")
		)
		(pad "1" smd rect
			(at -0.94996 0)
			(size 1.1176 1.3716)
			(layers "F.Cu" "F.Mask" "F.Paste")
			(net "SW_P1V0_AUX_FLT")
		)
		(pad "2" smd rect
			(at 0.94996 0)
			(size 1.1176 1.3716)
			(layers "F.Cu" "F.Mask" "F.Paste")
			(net "GND")
		)
	)
	(footprint ""
		(layer "F.Cu")
		(at 28.935172 -83.816952 90)
		(property "Reference" "R654"
			(at 0 0 90)
			(layer "F.SilkS")
			(hide yes)
			(effects
				(font
					(size 1.27 1.27)
				)
			)
		)
		(property "Value" ""
			(at 0 0 90)
			(layer "F.Fab")
			(effects
				(font
					(size 1.27 1.27)
				)
			)
		)
		(duplicate_pad_numbers_are_jumpers no)
		(fp_line
			(start 0.7874 -0.4064)
			(end 0.7874 0.4064)
			(stroke
				(width 0.1524)
				(type default)
			)
			(layer "F.SilkS")
		)
		(fp_line
			(start -0.7874 -0.4064)
			(end 0.7874 -0.4064)
			(stroke
				(width 0.1524)
				(type default)
			)
			(layer "F.SilkS")
		)
		(fp_line
			(start 0.7874 0.4064)
			(end -0.7874 0.4064)
			(stroke
				(width 0.1524)
				(type default)
			)
			(layer "F.SilkS")
		)
		(fp_line
			(start -0.7874 0.4064)
			(end -0.7874 -0.4064)
			(stroke
				(width 0.1524)
				(type default)
			)
			(layer "F.SilkS")
		)
		(fp_line
			(start -0.12065 -0.305054)
			(end -0.12065 -0.2794)
			(stroke
				(width 0.1)
				(type default)
			)
			(layer "F.Fab")
		)
		(fp_line
			(start -0.67945 -0.305054)
			(end -0.12065 -0.305054)
			(stroke
				(width 0.1)
				(type default)
			)
			(layer "F.Fab")
		)
		(fp_line
			(start 0.67945 -0.3048)
			(end 0.67945 0.3048)
			(stroke
				(width 0.1)
				(type default)
			)
			(layer "F.Fab")
		)
		(fp_line
			(start 0.12065 -0.3048)
			(end 0.67945 -0.3048)
			(stroke
				(width 0.1)
				(type default)
			)
			(layer "F.Fab")
		)
		(fp_line
			(start 0.12065 -0.2794)
			(end 0.12065 -0.3048)
			(stroke
				(width 0.1)
				(type default)
			)
			(layer "F.Fab")
		)
		(fp_line
			(start -0.12065 -0.2794)
			(end 0.12065 -0.2794)
			(stroke
				(width 0.1)
				(type default)
			)
			(layer "F.Fab")
		)
		(fp_line
			(start 0.120396 0.2794)
			(end -0.12065 0.2794)
			(stroke
				(width 0.1)
				(type default)
			)
			(layer "F.Fab")
		)
		(fp_line
			(start -0.12065 0.2794)
			(end -0.12065 0.3048)
			(stroke
				(width 0.1)
				(type default)
			)
			(layer "F.Fab")
		)
		(fp_line
			(start 0.67945 0.3048)
			(end 0.120396 0.3048)
			(stroke
				(width 0.1)
				(type default)
			)
			(layer "F.Fab")
		)
		(fp_line
			(start 0.120396 0.3048)
			(end 0.120396 0.2794)
			(stroke
				(width 0.1)
				(type default)
			)
			(layer "F.Fab")
		)
		(fp_line
			(start -0.12065 0.3048)
			(end -0.67945 0.3048)
			(stroke
				(width 0.1)
				(type default)
			)
			(layer "F.Fab")
		)
		(fp_line
			(start -0.67945 0.3048)
			(end -0.67945 -0.305054)
			(stroke
				(width 0.1)
				(type default)
			)
			(layer "F.Fab")
		)
		(pad "1" smd circle
			(at -0.40005 0 90)
			(size 0 0)
			(layers "F.Cu" "F.Mask" "F.Paste")
			(net "EMMC_CLK_R")
		)
		(pad "2" smd circle
			(at 0.40005 0 90)
			(size 0 0)
			(layers "F.Cu" "F.Mask" "F.Paste")
			(net "BMC_EMMC_CLK")
		)
	)
	(footprint ""
		(layer "F.Cu")
		(at 55.4228 -63.6524 90)
		(property "Reference" "R681"
			(at 0 0 90)
			(layer "F.SilkS")
			(hide yes)
			(effects
				(font
					(size 1.27 1.27)
				)
			)
		)
		(property "Value" ""
			(at 0 0 90)
			(layer "F.Fab")
			(effects
				(font
					(size 1.27 1.27)
				)
			)
		)
		(duplicate_pad_numbers_are_jumpers no)
		(fp_line
			(start 0.7874 -0.4064)
			(end 0.7874 0.4064)
			(stroke
				(width 0.1524)
				(type default)
			)
			(layer "F.SilkS")
		)
		(fp_line
			(start -0.7874 -0.4064)
			(end 0.7874 -0.4064)
			(stroke
				(width 0.1524)
				(type default)
			)
			(layer "F.SilkS")
		)
		(fp_line
			(start 0.7874 0.4064)
			(end -0.7874 0.4064)
			(stroke
				(width 0.1524)
				(type default)
			)
			(layer "F.SilkS")
		)
		(fp_line
			(start -0.7874 0.4064)
			(end -0.7874 -0.4064)
			(stroke
				(width 0.1524)
				(type default)
			)
			(layer "F.SilkS")
		)
		(fp_line
			(start -0.12065 -0.305054)
			(end -0.12065 -0.2794)
			(stroke
				(width 0.1)
				(type default)
			)
			(layer "F.Fab")
		)
		(fp_line
			(start -0.67945 -0.305054)
			(end -0.12065 -0.305054)
			(stroke
				(width 0.1)
				(type default)
			)
			(layer "F.Fab")
		)
		(fp_line
			(start 0.67945 -0.3048)
			(end 0.67945 0.3048)
			(stroke
				(width 0.1)
				(type default)
			)
			(layer "F.Fab")
		)
		(fp_line
			(start 0.12065 -0.3048)
			(end 0.67945 -0.3048)
			(stroke
				(width 0.1)
				(type default)
			)
			(layer "F.Fab")
		)
		(fp_line
			(start 0.12065 -0.2794)
			(end 0.12065 -0.3048)
			(stroke
				(width 0.1)
				(type default)
			)
			(layer "F.Fab")
		)
		(fp_line
			(start -0.12065 -0.2794)
			(end 0.12065 -0.2794)
			(stroke
				(width 0.1)
				(type default)
			)
			(layer "F.Fab")
		)
		(fp_line
			(start 0.120396 0.2794)
			(end -0.12065 0.2794)
			(stroke
				(width 0.1)
				(type default)
			)
			(layer "F.Fab")
		)
		(fp_line
			(start -0.12065 0.2794)
			(end -0.12065 0.3048)
			(stroke
				(width 0.1)
				(type default)
			)
			(layer "F.Fab")
		)
		(fp_line
			(start 0.67945 0.3048)
			(end 0.120396 0.3048)
			(stroke
				(width 0.1)
				(type default)
			)
			(layer "F.Fab")
		)
		(fp_line
			(start 0.120396 0.3048)
			(end 0.120396 0.2794)
			(stroke
				(width 0.1)
				(type default)
			)
			(layer "F.Fab")
		)
		(fp_line
			(start -0.12065 0.3048)
			(end -0.67945 0.3048)
			(stroke
				(width 0.1)
				(type default)
			)
			(layer "F.Fab")
		)
		(fp_line
			(start -0.67945 0.3048)
			(end -0.67945 -0.305054)
			(stroke
				(width 0.1)
				(type default)
			)
			(layer "F.Fab")
		)
		(pad "1" smd circle
			(at -0.40005 0 90)
			(size 0 0)
			(layers "F.Cu" "F.Mask" "F.Paste")
			(net "SPI_BMC_IO2_R")
		)
		(pad "2" smd circle
			(at 0.40005 0 90)
			(size 0 0)
			(layers "F.Cu" "F.Mask" "F.Paste")
			(net "QSPI_2_PLD_IO2")
		)
	)
)
